(kicad_pcb
	(version 20241229)
	(generator "pcbnew")
	(generator_version "9.0")
	(general
		(thickness 1.292)
		(legacy_teardrops no)
	)
	(paper "A4")
	(title_block
		(title "LPDDR5 Testbed")
		(date "2023-12-19")
		(rev "1.0.0")
		(comment 9 "footprints 114-120 of 160")
	)
	(layers
		(0 "F.Cu" signal)
		(4 "In1.Cu" power)
		(6 "In2.Cu" power)
		(8 "In3.Cu" signal)
		(10 "In4.Cu" signal)
		(2 "B.Cu" signal)
		(9 "F.Adhes" user "F.Adhesive")
		(11 "B.Adhes" user "B.Adhesive")
		(13 "F.Paste" user)
		(15 "B.Paste" user)
		(5 "F.SilkS" user "F.Silkscreen")
		(7 "B.SilkS" user "B.Silkscreen")
		(1 "F.Mask" user)
		(3 "B.Mask" user)
		(17 "Dwgs.User" user "User.Drawings")
		(19 "Cmts.User" user "User.Comments")
		(21 "Eco1.User" user "User.Eco1")
		(23 "Eco2.User" user "User.Eco2")
		(25 "Edge.Cuts" user)
		(27 "Margin" user)
		(31 "F.CrtYd" user "F.Courtyard")
		(29 "B.CrtYd" user "B.Courtyard")
		(35 "F.Fab" user)
		(33 "B.Fab" user)
	)
	(footprint "antmicro-footprints:C_0402_1005Metric"
		(layer "B.Cu")
		(at 129.175 74.95 180)
		(descr "Capacitor SMD 0402")
		(tags "capacitor SMD 0402")
		(property "Reference" "C40"
			(at 1.075 -0.35 0)
			(unlocked yes)
			(layer "B.SilkS")
			(effects
				(font
					(size 0.7 0.7)
					(thickness 0.15)
				)
				(justify left bottom mirror)
			)
		)
		(property "Value" "C_4u7_0402"
			(at -1.022927 -2.155213 0)
			(layer "B.Fab")
			(effects
				(font
					(size 0.7 0.7)
					(thickness 0.15)
				)
				(justify left bottom mirror)
			)
		)
		(property "Author" "Antmicro"
			(at 258.35 149.9 0)
			(layer "B.Fab")
			(hide yes)
			(effects
				(font
					(size 1 1)
					(thickness 0.15)
				)
				(justify mirror)
			)
		)
		(property "Dielectric" ""
			(at 258.35 149.9 0)
			(layer "B.Fab")
			(hide yes)
			(effects
				(font
					(size 1 1)
					(thickness 0.15)
				)
				(justify mirror)
			)
		)
		(property "License" "Apache-2.0"
			(at 258.35 149.9 0)
			(layer "B.Fab")
			(hide yes)
			(effects
				(font
					(size 1 1)
					(thickness 0.15)
				)
				(justify mirror)
			)
		)
		(property "MPN" "GRM155R61A475MEAAD"
			(at 258.35 149.9 0)
			(layer "B.Fab")
			(hide yes)
			(effects
				(font
					(size 1 1)
					(thickness 0.15)
				)
				(justify mirror)
			)
		)
		(property "Manufacturer" "Murata"
			(at 258.35 149.9 0)
			(layer "B.Fab")
			(hide yes)
			(effects
				(font
					(size 1 1)
					(thickness 0.15)
				)
				(justify mirror)
			)
		)
		(property "Val" "4u7"
			(at 258.35 149.9 0)
			(layer "B.Fab")
			(hide yes)
			(effects
				(font
					(size 1 1)
					(thickness 0.15)
				)
				(justify mirror)
			)
		)
		(property "Voltage" ""
			(at 258.35 149.9 0)
			(layer "B.Fab")
			(hide yes)
			(effects
				(font
					(size 1 1)
					(thickness 0.15)
				)
				(justify mirror)
			)
		)
		(sheetname "LPDDR5")
		(sheetfile "lpddr5.kicad_sch")
		(attr smd)
		(fp_rect
			(start -0.9659 0.481258)
			(end 0.9649 -0.458742)
			(stroke
				(width 0.05)
				(type solid)
			)
			(fill no)
			(layer "B.CrtYd")
		)
		(fp_line
			(start 0.499 0.25)
			(end 0.499 -0.248)
			(stroke
				(width 0.15)
				(type solid)
			)
			(layer "B.Fab")
		)
		(fp_line
			(start 0.499 -0.248)
			(end -0.499 -0.248)
			(stroke
				(width 0.15)
				(type solid)
			)
			(layer "B.Fab")
		)
		(fp_line
			(start -0.499 0.25)
			(end 0.499 0.25)
			(stroke
				(width 0.15)
				(type solid)
			)
			(layer "B.Fab")
		)
		(fp_line
			(start -0.499 -0.248)
			(end -0.499 0.25)
			(stroke
				(width 0.15)
				(type solid)
			)
			(layer "B.Fab")
		)
		(pad "1" smd roundrect
			(at -0.484 0 180)
			(size 0.59 0.64)
			(layers "B.Cu" "B.Mask" "B.Paste")
			(roundrect_rratio 0.25)
			(net 14 "GND")
			(pintype "passive")
		)
		(pad "2" smd roundrect
			(at 0.484 0 180)
			(size 0.59 0.64)
			(layers "B.Cu" "B.Mask" "B.Paste")
			(roundrect_rratio 0.25)
			(net 4 "+0V5")
			(pintype "passive")
		)
	)
	(footprint "antmicro-footprints:C_0402_1005Metric"
		(layer "B.Cu")
		(at 131.975 75.55 90)
		(descr "Capacitor SMD 0402")
		(tags "capacitor SMD 0402")
		(property "Reference" "C47"
			(at 1.25 0.699 90)
			(unlocked yes)
			(layer "B.SilkS")
			(effects
				(font
					(size 0.7 0.7)
					(thickness 0.15)
				)
				(justify right bottom mirror)
			)
		)
		(property "Value" "C_4u7_0402"
			(at -1.022927 -2.155213 90)
			(layer "B.Fab")
			(effects
				(font
					(size 0.7 0.7)
					(thickness 0.15)
				)
				(justify right bottom mirror)
			)
		)
		(property "Author" "Antmicro"
			(at 207.525 -56.425 0)
			(layer "B.Fab")
			(hide yes)
			(effects
				(font
					(size 1 1)
					(thickness 0.15)
				)
				(justify mirror)
			)
		)
		(property "Dielectric" ""
			(at 207.525 -56.425 0)
			(layer "B.Fab")
			(hide yes)
			(effects
				(font
					(size 1 1)
					(thickness 0.15)
				)
				(justify mirror)
			)
		)
		(property "License" "Apache-2.0"
			(at 207.525 -56.425 0)
			(layer "B.Fab")
			(hide yes)
			(effects
				(font
					(size 1 1)
					(thickness 0.15)
				)
				(justify mirror)
			)
		)
		(property "MPN" "GRM155R61A475MEAAD"
			(at 207.525 -56.425 0)
			(layer "B.Fab")
			(hide yes)
			(effects
				(font
					(size 1 1)
					(thickness 0.15)
				)
				(justify mirror)
			)
		)
		(property "Manufacturer" "Murata"
			(at 207.525 -56.425 0)
			(layer "B.Fab")
			(hide yes)
			(effects
				(font
					(size 1 1)
					(thickness 0.15)
				)
				(justify mirror)
			)
		)
		(property "Val" "4u7"
			(at 207.525 -56.425 0)
			(layer "B.Fab")
			(hide yes)
			(effects
				(font
					(size 1 1)
					(thickness 0.15)
				)
				(justify mirror)
			)
		)
		(property "Voltage" ""
			(at 207.525 -56.425 0)
			(layer "B.Fab")
			(hide yes)
			(effects
				(font
					(size 1 1)
					(thickness 0.15)
				)
				(justify mirror)
			)
		)
		(sheetname "LPDDR5")
		(sheetfile "lpddr5.kicad_sch")
		(attr smd)
		(fp_rect
			(start -0.9659 0.481258)
			(end 0.9649 -0.458742)
			(stroke
				(width 0.05)
				(type solid)
			)
			(fill no)
			(layer "B.CrtYd")
		)
		(fp_line
			(start 0.499 -0.248)
			(end -0.499 -0.248)
			(stroke
				(width 0.15)
				(type solid)
			)
			(layer "B.Fab")
		)
		(fp_line
			(start -0.499 -0.248)
			(end -0.499 0.25)
			(stroke
				(width 0.15)
				(type solid)
			)
			(layer "B.Fab")
		)
		(fp_line
			(start 0.499 0.25)
			(end 0.499 -0.248)
			(stroke
				(width 0.15)
				(type solid)
			)
			(layer "B.Fab")
		)
		(fp_line
			(start -0.499 0.25)
			(end 0.499 0.25)
			(stroke
				(width 0.15)
				(type solid)
			)
			(layer "B.Fab")
		)
		(pad "1" smd roundrect
			(at -0.484 0 90)
			(size 0.59 0.64)
			(layers "B.Cu" "B.Mask" "B.Paste")
			(roundrect_rratio 0.25)
			(net 14 "GND")
			(pintype "passive")
		)
		(pad "2" smd roundrect
			(at 0.484 0 90)
			(size 0.59 0.64)
			(layers "B.Cu" "B.Mask" "B.Paste")
			(roundrect_rratio 0.25)
			(net 4 "+0V5")
			(pintype "passive")
		)
	)
	(footprint "antmicro-footprints:R_0402_1005Metric"
		(layer "B.Cu")
		(at 134.9 93.8425 -90)
		(descr "Resistor SMD 0402")
		(tags "resistor SMD 0402")
		(property "Reference" "R28"
			(at 0.8575 -0.3 90)
			(unlocked yes)
			(layer "B.SilkS")
			(effects
				(font
					(size 0.7 0.7)
					(thickness 0.15)
				)
				(justify left bottom mirror)
			)
		)
		(property "Value" "R_200k_0402"
			(at -1.011843 -1.772047 90)
			(layer "B.Fab")
			(effects
				(font
					(size 0.7 0.7)
					(thickness 0.15)
				)
				(justify left bottom mirror)
			)
		)
		(property "Author" "Antmicro"
			(at 41.0575 228.7425 0)
			(layer "B.Fab")
			(hide yes)
			(effects
				(font
					(size 1 1)
					(thickness 0.15)
				)
				(justify mirror)
			)
		)
		(property "License" "Apache-2.0"
			(at 41.0575 228.7425 0)
			(layer "B.Fab")
			(hide yes)
			(effects
				(font
					(size 1 1)
					(thickness 0.15)
				)
				(justify mirror)
			)
		)
		(property "MPN" "CR0402-FX-2003GLF"
			(at 41.0575 228.7425 0)
			(layer "B.Fab")
			(hide yes)
			(effects
				(font
					(size 1 1)
					(thickness 0.15)
				)
				(justify mirror)
			)
		)
		(property "Manufacturer" "Bourns"
			(at 41.0575 228.7425 0)
			(layer "B.Fab")
			(hide yes)
			(effects
				(font
					(size 1 1)
					(thickness 0.15)
				)
				(justify mirror)
			)
		)
		(property "Tolerance" "1%"
			(at 41.0575 228.7425 0)
			(layer "B.Fab")
			(hide yes)
			(effects
				(font
					(size 1 1)
					(thickness 0.15)
				)
				(justify mirror)
			)
		)
		(property "Val" "200k"
			(at 41.0575 228.7425 0)
			(layer "B.Fab")
			(hide yes)
			(effects
				(font
					(size 1 1)
					(thickness 0.15)
				)
				(justify mirror)
			)
		)
		(sheetname "SODIMM")
		(sheetfile "sodim.kicad_sch")
		(attr smd exclude_from_pos_files exclude_from_bom dnp)
		(fp_rect
			(start -0.93 0.47)
			(end 0.93 -0.47)
			(stroke
				(width 0.05)
				(type solid)
			)
			(fill no)
			(layer "B.CrtYd")
		)
		(fp_rect
			(start -0.5 0.25)
			(end 0.5 -0.25)
			(stroke
				(width 0.15)
				(type solid)
			)
			(fill no)
			(layer "B.Fab")
		)
		(pad "1" smd roundrect
			(at -0.485 0 270)
			(size 0.59 0.64)
			(layers "B.Cu" "B.Mask" "B.Paste")
			(roundrect_rratio 0.25)
			(net 5 "+5V")
			(pintype "passive")
		)
		(pad "2" smd roundrect
			(at 0.485 0 270)
			(size 0.59 0.64)
			(layers "B.Cu" "B.Mask" "B.Paste")
			(roundrect_rratio 0.25)
			(net 33 "Net-(J1-Pad130)")
			(pintype "passive")
		)
	)
	(footprint "antmicro-footprints:R_0402_1005Metric"
		(layer "B.Cu")
		(at 107.63 90.97 90)
		(descr "Resistor SMD 0402")
		(tags "resistor SMD 0402")
		(property "Reference" "R14"
			(at -1.23 1.37 90)
			(unlocked yes)
			(layer "B.SilkS")
			(effects
				(font
					(size 0.7 0.7)
					(thickness 0.15)
				)
				(justify right bottom mirror)
			)
		)
		(property "Value" "R_100R_0402"
			(at -1.011843 -1.772047 90)
			(layer "B.Fab")
			(effects
				(font
					(size 0.7 0.7)
					(thickness 0.15)
				)
				(justify right bottom mirror)
			)
		)
		(property "Author" "Antmicro"
			(at 198.6 -16.66 0)
			(layer "B.Fab")
			(hide yes)
			(effects
				(font
					(size 1 1)
					(thickness 0.15)
				)
				(justify mirror)
			)
		)
		(property "License" "Apache-2.0"
			(at 198.6 -16.66 0)
			(layer "B.Fab")
			(hide yes)
			(effects
				(font
					(size 1 1)
					(thickness 0.15)
				)
				(justify mirror)
			)
		)
		(property "MPN" "CR0402-FX-1000GLF"
			(at 198.6 -16.66 0)
			(layer "B.Fab")
			(hide yes)
			(effects
				(font
					(size 1 1)
					(thickness 0.15)
				)
				(justify mirror)
			)
		)
		(property "Manufacturer" "Bourns"
			(at 198.6 -16.66 0)
			(layer "B.Fab")
			(hide yes)
			(effects
				(font
					(size 1 1)
					(thickness 0.15)
				)
				(justify mirror)
			)
		)
		(property "Tolerance" "1%"
			(at 198.6 -16.66 0)
			(layer "B.Fab")
			(hide yes)
			(effects
				(font
					(size 1 1)
					(thickness 0.15)
				)
				(justify mirror)
			)
		)
		(property "Val" "100R"
			(at 198.6 -16.66 0)
			(layer "B.Fab")
			(hide yes)
			(effects
				(font
					(size 1 1)
					(thickness 0.15)
				)
				(justify mirror)
			)
		)
		(sheetname "Translators")
		(sheetfile "translators.kicad_sch")
		(attr smd)
		(fp_rect
			(start -0.93 0.47)
			(end 0.93 -0.47)
			(stroke
				(width 0.05)
				(type solid)
			)
			(fill no)
			(layer "B.CrtYd")
		)
		(fp_rect
			(start -0.5 0.25)
			(end 0.5 -0.25)
			(stroke
				(width 0.15)
				(type solid)
			)
			(fill no)
			(layer "B.Fab")
		)
		(pad "1" smd roundrect
			(at -0.485 0 90)
			(size 0.59 0.64)
			(layers "B.Cu" "B.Mask" "B.Paste")
			(roundrect_rratio 0.25)
			(net 181 "/SODIMM/LPDDR5_IN_A.WCK1_P")
			(pintype "passive")
		)
		(pad "2" smd roundrect
			(at 0.485 0 90)
			(size 0.59 0.64)
			(layers "B.Cu" "B.Mask" "B.Paste")
			(roundrect_rratio 0.25)
			(net 48 "/LPDDR5/LPDDR5_A.WCK1_P")
			(pintype "passive")
		)
	)
	(footprint "antmicro-footprints:C_0402_1005Metric"
		(layer "B.Cu")
		(at 142.575 80.75 180)
		(descr "Capacitor SMD 0402")
		(tags "capacitor SMD 0402")
		(property "Reference" "C61"
			(at -3.225 -0.25 0)
			(unlocked yes)
			(layer "B.SilkS")
			(effects
				(font
					(size 0.7 0.7)
					(thickness 0.15)
				)
				(justify left bottom mirror)
			)
		)
		(property "Value" "C_4u7_0402"
			(at -1.022927 -2.155213 0)
			(layer "B.Fab")
			(effects
				(font
					(size 0.7 0.7)
					(thickness 0.15)
				)
				(justify left bottom mirror)
			)
		)
		(property "Author" "Antmicro"
			(at 285.15 161.5 0)
			(layer "B.Fab")
			(hide yes)
			(effects
				(font
					(size 1 1)
					(thickness 0.15)
				)
				(justify mirror)
			)
		)
		(property "Dielectric" ""
			(at 285.15 161.5 0)
			(layer "B.Fab")
			(hide yes)
			(effects
				(font
					(size 1 1)
					(thickness 0.15)
				)
				(justify mirror)
			)
		)
		(property "License" "Apache-2.0"
			(at 285.15 161.5 0)
			(layer "B.Fab")
			(hide yes)
			(effects
				(font
					(size 1 1)
					(thickness 0.15)
				)
				(justify mirror)
			)
		)
		(property "MPN" "GRM155R61A475MEAAD"
			(at 285.15 161.5 0)
			(layer "B.Fab")
			(hide yes)
			(effects
				(font
					(size 1 1)
					(thickness 0.15)
				)
				(justify mirror)
			)
		)
		(property "Manufacturer" "Murata"
			(at 285.15 161.5 0)
			(layer "B.Fab")
			(hide yes)
			(effects
				(font
					(size 1 1)
					(thickness 0.15)
				)
				(justify mirror)
			)
		)
		(property "Val" "4u7"
			(at 285.15 161.5 0)
			(layer "B.Fab")
			(hide yes)
			(effects
				(font
					(size 1 1)
					(thickness 0.15)
				)
				(justify mirror)
			)
		)
		(property "Voltage" ""
			(at 285.15 161.5 0)
			(layer "B.Fab")
			(hide yes)
			(effects
				(font
					(size 1 1)
					(thickness 0.15)
				)
				(justify mirror)
			)
		)
		(sheetname "LPDDR5")
		(sheetfile "lpddr5.kicad_sch")
		(attr smd)
		(fp_rect
			(start -0.9659 0.481258)
			(end 0.9649 -0.458742)
			(stroke
				(width 0.05)
				(type solid)
			)
			(fill no)
			(layer "B.CrtYd")
		)
		(fp_line
			(start 0.499 0.25)
			(end 0.499 -0.248)
			(stroke
				(width 0.15)
				(type solid)
			)
			(layer "B.Fab")
		)
		(fp_line
			(start 0.499 -0.248)
			(end -0.499 -0.248)
			(stroke
				(width 0.15)
				(type solid)
			)
			(layer "B.Fab")
		)
		(fp_line
			(start -0.499 0.25)
			(end 0.499 0.25)
			(stroke
				(width 0.15)
				(type solid)
			)
			(layer "B.Fab")
		)
		(fp_line
			(start -0.499 -0.248)
			(end -0.499 0.25)
			(stroke
				(width 0.15)
				(type solid)
			)
			(layer "B.Fab")
		)
		(pad "1" smd roundrect
			(at -0.484 0 180)
			(size 0.59 0.64)
			(layers "B.Cu" "B.Mask" "B.Paste")
			(roundrect_rratio 0.25)
			(net 14 "GND")
			(pintype "passive")
		)
		(pad "2" smd roundrect
			(at 0.484 0 180)
			(size 0.59 0.64)
			(layers "B.Cu" "B.Mask" "B.Paste")
			(roundrect_rratio 0.25)
			(net 13 "+1V05")
			(pintype "passive")
		)
	)
	(footprint "antmicro-footprints:C_0402_1005Metric"
		(layer "B.Cu")
		(at 131.275 77.5 180)
		(descr "Capacitor SMD 0402")
		(tags "capacitor SMD 0402")
		(property "Reference" "C42"
			(at 0 0.699 0)
			(unlocked yes)
			(layer "B.SilkS")
			(effects
				(font
					(size 0.7 0.7)
					(thickness 0.15)
				)
				(justify left bottom mirror)
			)
		)
		(property "Value" "C_4u7_0402"
			(at -1.022927 -2.155213 0)
			(layer "B.Fab")
			(effects
				(font
					(size 0.7 0.7)
					(thickness 0.15)
				)
				(justify left bottom mirror)
			)
		)
		(property "Author" "Antmicro"
			(at 262.55 155 0)
			(layer "B.Fab")
			(hide yes)
			(effects
				(font
					(size 1 1)
					(thickness 0.15)
				)
				(justify mirror)
			)
		)
		(property "Dielectric" ""
			(at 262.55 155 0)
			(layer "B.Fab")
			(hide yes)
			(effects
				(font
					(size 1 1)
					(thickness 0.15)
				)
				(justify mirror)
			)
		)
		(property "License" "Apache-2.0"
			(at 262.55 155 0)
			(layer "B.Fab")
			(hide yes)
			(effects
				(font
					(size 1 1)
					(thickness 0.15)
				)
				(justify mirror)
			)
		)
		(property "MPN" "GRM155R61A475MEAAD"
			(at 262.55 155 0)
			(layer "B.Fab")
			(hide yes)
			(effects
				(font
					(size 1 1)
					(thickness 0.15)
				)
				(justify mirror)
			)
		)
		(property "Manufacturer" "Murata"
			(at 262.55 155 0)
			(layer "B.Fab")
			(hide yes)
			(effects
				(font
					(size 1 1)
					(thickness 0.15)
				)
				(justify mirror)
			)
		)
		(property "Val" "4u7"
			(at 262.55 155 0)
			(layer "B.Fab")
			(hide yes)
			(effects
				(font
					(size 1 1)
					(thickness 0.15)
				)
				(justify mirror)
			)
		)
		(property "Voltage" ""
			(at 262.55 155 0)
			(layer "B.Fab")
			(hide yes)
			(effects
				(font
					(size 1 1)
					(thickness 0.15)
				)
				(justify mirror)
			)
		)
		(sheetname "LPDDR5")
		(sheetfile "lpddr5.kicad_sch")
		(attr smd)
		(fp_rect
			(start -0.9659 0.481258)
			(end 0.9649 -0.458742)
			(stroke
				(width 0.05)
				(type solid)
			)
			(fill no)
			(layer "B.CrtYd")
		)
		(fp_line
			(start 0.499 0.25)
			(end 0.499 -0.248)
			(stroke
				(width 0.15)
				(type solid)
			)
			(layer "B.Fab")
		)
		(fp_line
			(start 0.499 -0.248)
			(end -0.499 -0.248)
			(stroke
				(width 0.15)
				(type solid)
			)
			(layer "B.Fab")
		)
		(fp_line
			(start -0.499 0.25)
			(end 0.499 0.25)
			(stroke
				(width 0.15)
				(type solid)
			)
			(layer "B.Fab")
		)
		(fp_line
			(start -0.499 -0.248)
			(end -0.499 0.25)
			(stroke
				(width 0.15)
				(type solid)
			)
			(layer "B.Fab")
		)
		(pad "1" smd roundrect
			(at -0.484 0 180)
			(size 0.59 0.64)
			(layers "B.Cu" "B.Mask" "B.Paste")
			(roundrect_rratio 0.25)
			(net 14 "GND")
			(pintype "passive")
		)
		(pad "2" smd roundrect
			(at 0.484 0 180)
			(size 0.59 0.64)
			(layers "B.Cu" "B.Mask" "B.Paste")
			(roundrect_rratio 0.25)
			(net 4 "+0V5")
			(pintype "passive")
		)
	)
	(footprint "antmicro-footprints:C_0402_1005Metric"
		(layer "B.Cu")
		(at 131.975 84.35 -90)
		(descr "Capacitor SMD 0402")
		(tags "capacitor SMD 0402")
		(property "Reference" "C50"
			(at 0.85 -0.425 90)
			(unlocked yes)
			(layer "B.SilkS")
			(effects
				(font
					(size 0.7 0.7)
					(thickness 0.15)
				)
				(justify left bottom mirror)
			)
		)
		(property "Value" "C_4u7_0402"
			(at -1.022927 -2.155213 90)
			(layer "B.Fab")
			(effects
				(font
					(size 0.7 0.7)
					(thickness 0.15)
				)
				(justify left bottom mirror)
			)
		)
		(property "Author" "Antmicro"
			(at 47.625 216.325 0)
			(layer "B.Fab")
			(hide yes)
			(effects
				(font
					(size 1 1)
					(thickness 0.15)
				)
				(justify mirror)
			)
		)
		(property "Dielectric" ""
			(at 47.625 216.325 0)
			(layer "B.Fab")
			(hide yes)
			(effects
				(font
					(size 1 1)
					(thickness 0.15)
				)
				(justify mirror)
			)
		)
		(property "License" "Apache-2.0"
			(at 47.625 216.325 0)
			(layer "B.Fab")
			(hide yes)
			(effects
				(font
					(size 1 1)
					(thickness 0.15)
				)
				(justify mirror)
			)
		)
		(property "MPN" "GRM155R61A475MEAAD"
			(at 47.625 216.325 0)
			(layer "B.Fab")
			(hide yes)
			(effects
				(font
					(size 1 1)
					(thickness 0.15)
				)
				(justify mirror)
			)
		)
		(property "Manufacturer" "Murata"
			(at 47.625 216.325 0)
			(layer "B.Fab")
			(hide yes)
			(effects
				(font
					(size 1 1)
					(thickness 0.15)
				)
				(justify mirror)
			)
		)
		(property "Val" "4u7"
			(at 47.625 216.325 0)
			(layer "B.Fab")
			(hide yes)
			(effects
				(font
					(size 1 1)
					(thickness 0.15)
				)
				(justify mirror)
			)
		)
		(property "Voltage" ""
			(at 47.625 216.325 0)
			(layer "B.Fab")
			(hide yes)
			(effects
				(font
					(size 1 1)
					(thickness 0.15)
				)
				(justify mirror)
			)
		)
		(sheetname "LPDDR5")
		(sheetfile "lpddr5.kicad_sch")
		(attr smd)
		(fp_rect
			(start -0.9659 0.481258)
			(end 0.9649 -0.458742)
			(stroke
				(width 0.05)
				(type solid)
			)
			(fill no)
			(layer "B.CrtYd")
		)
		(fp_line
			(start -0.499 0.25)
			(end 0.499 0.25)
			(stroke
				(width 0.15)
				(type solid)
			)
			(layer "B.Fab")
		)
		(fp_line
			(start 0.499 0.25)
			(end 0.499 -0.248)
			(stroke
				(width 0.15)
				(type solid)
			)
			(layer "B.Fab")
		)
		(fp_line
			(start -0.499 -0.248)
			(end -0.499 0.25)
			(stroke
				(width 0.15)
				(type solid)
			)
			(layer "B.Fab")
		)
		(fp_line
			(start 0.499 -0.248)
			(end -0.499 -0.248)
			(stroke
				(width 0.15)
				(type solid)
			)
			(layer "B.Fab")
		)
		(pad "1" smd roundrect
			(at -0.484 0 270)
			(size 0.59 0.64)
			(layers "B.Cu" "B.Mask" "B.Paste")
			(roundrect_rratio 0.25)
			(net 14 "GND")
			(pintype "passive")
		)
		(pad "2" smd roundrect
			(at 0.484 0 270)
			(size 0.59 0.64)
			(layers "B.Cu" "B.Mask" "B.Paste")
			(roundrect_rratio 0.25)
			(net 4 "+0V5")
			(pintype "passive")
		)
	)
)
